(kicad_pcb
	(version 20211014)
	(generator pcbnew)
	(general
    (thickness 1.6)
  )
	(paper "A4")
	(title_block
    (title "SA800U (Snapdragon 845) Baseboard")
    (date "2023-10-19")
    (rev "1.0.3")
    (company "Antmicro Ltd.")
    (comment 1 "www.antmicro.com")
		(comment 9 "footprints 71-80 of 589")
	)
	(layers
    (0 "F.Cu" signal)
    (1 "In1.Cu" power)
    (2 "In2.Cu" signal)
    (3 "In3.Cu" signal)
    (4 "In4.Cu" power)
    (31 "B.Cu" signal)
    (32 "B.Adhes" user "B.Adhesive")
    (33 "F.Adhes" user "F.Adhesive")
    (34 "B.Paste" user)
    (35 "F.Paste" user)
    (36 "B.SilkS" user "B.Silkscreen")
    (37 "F.SilkS" user "F.Silkscreen")
    (38 "B.Mask" user)
    (39 "F.Mask" user)
    (40 "Dwgs.User" user "User.Drawings")
    (41 "Cmts.User" user "User.Comments")
    (42 "Eco1.User" user "User.Eco1")
    (43 "Eco2.User" user "User.Eco2")
    (44 "Edge.Cuts" user)
    (45 "Margin" user)
    (46 "B.CrtYd" user "B.Courtyard")
    (47 "F.CrtYd" user "F.Courtyard")
    (48 "B.Fab" user)
    (49 "F.Fab" user)
  )
	(footprint "sa800u-baseboard-hw-footprints:C_0402_1005Metric" (layer "F.Cu")
    (tedit 616D63CF)
    (at 81.175 138.05 180)
    (descr "Capacitor SMD 0402")
    (tags "capacitor SMD 0402")
    (property "Author" "Antmicro")
    (property "Dielectric" "X5R")
    (property "License" "Apache-2.0")
    (property "MPN" "GRM155R61H104KE14D")
    (property "Manufacturer" "Murata")
    (property "Sheetfile" "usb-pd.kicad_sch")
    (property "Sheetname" "USB-PD")
    (property "Val" "100n")
    (property "Voltage" "50V")
    (attr smd)
    (fp_text reference "C155" (at 3.555 -1.47 180) (layer "F.SilkS")
      (effects (font (size 0.7 0.7) (thickness 0.15)) (justify left bottom))
    )
    (fp_text value "C_100n_0402" (at 0 1.4 180) (layer "F.Fab")
      (effects (font (size 0.7 0.7) (thickness 0.15)) (justify left bottom))
    )
    (fp_text user "Author: Antmicro" (at -0.932 4.17 180) (layer "F.Fab") hide
      (effects (font (size 0.7 0.7) (thickness 0.15)) (justify left bottom))
    )
    (fp_text user "License: Apache-2.0" (at -0.932 5.17 180) (layer "F.Fab") hide
      (effects (font (size 0.7 0.7) (thickness 0.15)) (justify left bottom))
    )
    (fp_text user "${REFERENCE}" (at -0.932 3.168 180) (layer "F.Fab") hide
      (effects (font (size 0.7 0.7) (thickness 0.15)) (justify left bottom))
    )
    (fp_rect (start -0.94 -0.47) (end 0.94 0.47) (layer "F.CrtYd") (width 0.05) (fill none))
    (fp_rect (start -0.499 -0.249) (end 0.499 0.249) (layer "F.Fab") (width 0.15) (fill none))
    (pad "1" smd roundrect (at -0.484 0 180) (size 0.59 0.64) (layers "F.Cu" "F.Paste" "F.Mask") (roundrect_rratio 0.25)
      (net 142 "PD_VDD") (pintype "passive"))
    (pad "2" smd roundrect (at 0.484 0 180) (size 0.59 0.64) (layers "F.Cu" "F.Paste" "F.Mask") (roundrect_rratio 0.25)
      (net 365 "Net-(C155-Pad2)") (pintype "passive"))
  )
	(footprint "sa800u-baseboard-hw-footprints:R_0402_1005Metric" (layer "F.Cu")
    (tedit 5FD9C158)
    (at 80.05 136.525 90)
    (descr "Resistor SMD 0402")
    (tags "resistor SMD 0402")
    (property "Author" "Antmicro")
    (property "License" "Apache-2.0")
    (property "MPN" "CR0402-FX-1003GLF")
    (property "Manufacturer" "Bourns")
    (property "Sheetfile" "usb-pd.kicad_sch")
    (property "Sheetname" "USB-PD")
    (property "Tolerance" "1%")
    (property "Val" "100k")
    (attr smd)
    (fp_text reference "R160" (at -1.765 -0.61 90) (layer "F.SilkS")
      (effects (font (size 0.7 0.7) (thickness 0.15)) (justify left bottom))
    )
    (fp_text value "R_100k_0402" (at 0 1.4 90) (layer "F.Fab")
      (effects (font (size 0.7 0.7) (thickness 0.15)) (justify left bottom))
    )
    (fp_text user "${REFERENCE}" (at -0.95 3.168 90) (layer "F.Fab") hide
      (effects (font (size 0.7 0.7) (thickness 0.15)) (justify left bottom))
    )
    (fp_text user "License: Apache-2.0" (at -0.95 5.169 90) (layer "F.Fab") hide
      (effects (font (size 0.7 0.7) (thickness 0.15)) (justify left bottom))
    )
    (fp_text user "Author: Antmicro" (at -0.95 4.169 90) (layer "F.Fab") hide
      (effects (font (size 0.7 0.7) (thickness 0.15)) (justify left bottom))
    )
    (fp_rect (start -0.93 -0.47) (end 0.93 0.47) (layer "F.CrtYd") (width 0.05) (fill none))
    (fp_rect (start -0.5 -0.25) (end 0.5 0.25) (layer "F.Fab") (width 0.15) (fill none))
    (pad "1" smd roundrect (at -0.485 0 90) (size 0.59 0.64) (layers "F.Cu" "F.Paste" "F.Mask") (roundrect_rratio 0.25)
      (net 107 "/USB-PD/PD_VBUS") (pintype "passive"))
    (pad "2" smd roundrect (at 0.485 0 90) (size 0.59 0.64) (layers "F.Cu" "F.Paste" "F.Mask") (roundrect_rratio 0.25)
      (net 391 "Net-(Q17-Pad4)") (pintype "passive"))
  )
	(footprint "sa800u-baseboard-hw-footprints:R_0402_1005Metric" (layer "F.Cu")
    (tedit 5FD9C158)
    (at 81.47 136.05)
    (descr "Resistor SMD 0402")
    (tags "resistor SMD 0402")
    (property "Author" "Antmicro")
    (property "License" "Apache-2.0")
    (property "MPN" "CR0402-FX-2202GLF")
    (property "Manufacturer" "Bourns")
    (property "Sheetfile" "usb-pd.kicad_sch")
    (property "Sheetname" "USB-PD")
    (property "Tolerance" "1%")
    (property "Val" "22k")
    (attr smd)
    (fp_text reference "R161" (at -1.71 -1.58) (layer "F.SilkS")
      (effects (font (size 0.7 0.7) (thickness 0.15)) (justify left bottom))
    )
    (fp_text value "R_22k_0402" (at 0 1.4) (layer "F.Fab")
      (effects (font (size 0.7 0.7) (thickness 0.15)) (justify left bottom))
    )
    (fp_text user "Author: Antmicro" (at -0.95 4.169) (layer "F.Fab") hide
      (effects (font (size 0.7 0.7) (thickness 0.15)) (justify left bottom))
    )
    (fp_text user "${REFERENCE}" (at -0.95 3.168) (layer "F.Fab") hide
      (effects (font (size 0.7 0.7) (thickness 0.15)) (justify left bottom))
    )
    (fp_text user "License: Apache-2.0" (at -0.95 5.169) (layer "F.Fab") hide
      (effects (font (size 0.7 0.7) (thickness 0.15)) (justify left bottom))
    )
    (fp_rect (start -0.93 -0.47) (end 0.93 0.47) (layer "F.CrtYd") (width 0.05) (fill none))
    (fp_rect (start -0.5 -0.25) (end 0.5 0.25) (layer "F.Fab") (width 0.15) (fill none))
    (pad "1" smd roundrect (at -0.485 0) (size 0.59 0.64) (layers "F.Cu" "F.Paste" "F.Mask") (roundrect_rratio 0.25)
      (net 391 "Net-(Q17-Pad4)") (pintype "passive"))
    (pad "2" smd roundrect (at 0.485 0) (size 0.59 0.64) (layers "F.Cu" "F.Paste" "F.Mask") (roundrect_rratio 0.25)
      (net 467 "/USB-PD/EN_SINK") (pintype "passive"))
  )
	(footprint "sa800u-baseboard-hw-footprints:R_0402_1005Metric" (layer "F.Cu")
    (tedit 5FD9C158)
    (at 81.45 137.05)
    (descr "Resistor SMD 0402")
    (tags "resistor SMD 0402")
    (property "Author" "Antmicro")
    (property "License" "Apache-2.0")
    (property "MPN" "CR0402-FX-1000GLF")
    (property "Manufacturer" "Bourns")
    (property "Sheetfile" "usb-pd.kicad_sch")
    (property "Sheetname" "USB-PD")
    (property "Tolerance" "1%")
    (property "Val" "100R")
    (attr smd)
    (fp_text reference "R166" (at -1.71 -1.58) (layer "F.SilkS")
      (effects (font (size 0.7 0.7) (thickness 0.15)) (justify left bottom))
    )
    (fp_text value "R_100R_0402" (at 0 1.4) (layer "F.Fab")
      (effects (font (size 0.7 0.7) (thickness 0.15)) (justify left bottom))
    )
    (fp_text user "${REFERENCE}" (at -0.95 3.168) (layer "F.Fab") hide
      (effects (font (size 0.7 0.7) (thickness 0.15)) (justify left bottom))
    )
    (fp_text user "Author: Antmicro" (at -0.95 4.169) (layer "F.Fab") hide
      (effects (font (size 0.7 0.7) (thickness 0.15)) (justify left bottom))
    )
    (fp_text user "License: Apache-2.0" (at -0.95 5.169) (layer "F.Fab") hide
      (effects (font (size 0.7 0.7) (thickness 0.15)) (justify left bottom))
    )
    (fp_rect (start -0.93 -0.47) (end 0.93 0.47) (layer "F.CrtYd") (width 0.05) (fill none))
    (fp_rect (start -0.5 -0.25) (end 0.5 0.25) (layer "F.Fab") (width 0.15) (fill none))
    (pad "1" smd roundrect (at -0.485 0) (size 0.59 0.64) (layers "F.Cu" "F.Paste" "F.Mask") (roundrect_rratio 0.25)
      (net 391 "Net-(Q17-Pad4)") (pintype "passive"))
    (pad "2" smd roundrect (at 0.485 0) (size 0.59 0.64) (layers "F.Cu" "F.Paste" "F.Mask") (roundrect_rratio 0.25)
      (net 365 "Net-(C155-Pad2)") (pintype "passive"))
  )
	(footprint "sa800u-baseboard-hw-footprints:D_SOD-323F" (layer "F.Cu")
    (tedit 60F16F6B)
    (at 81.5 141.4 -90)
    (property "Author" "Antmicro")
    (property "License" "Apache-2.0")
    (property "MPN" "PMEG6002EJ,115")
    (property "Manufacturer" "Nexperia")
    (property "Sheetfile" "usb-pd.kicad_sch")
    (property "Sheetname" "USB-PD")
    (attr smd)
    (fp_text reference "D35" (at 3.7 -0.5 -90) (layer "F.SilkS")
      (effects (font (size 0.7 0.7) (thickness 0.15)) (justify left bottom))
    )
    (fp_text value "PMEG6002EJ,115" (at -1.7 1.9 -90) (layer "F.Fab")
      (effects (font (size 0.7 0.7) (thickness 0.15)) (justify left bottom))
    )
    (fp_text user "Author: Antmicro" (at -1.8 4.46 -90) (layer "F.Fab") hide
      (effects (font (size 0.7 0.7) (thickness 0.15)) (justify left bottom))
    )
    (fp_text user "${REFERENCE}" (at -1.8 3.2 -90) (layer "F.Fab") hide
      (effects (font (size 0.7 0.7) (thickness 0.15)) (justify left bottom))
    )
    (fp_text user "License: Apache-2.0" (at -1.8 5.8 -90) (layer "F.Fab") hide
      (effects (font (size 0.7 0.7) (thickness 0.15)) (justify left bottom))
    )
    (fp_line (start 0.973 0.45) (end 0.973 0.748) (layer "F.SilkS") (width 0.15))
    (fp_line (start 0.623 -0.75) (end 0.973 -0.75) (layer "F.SilkS") (width 0.15))
    (fp_line (start -0.625 -0.75) (end -0.975 -0.75) (layer "F.SilkS") (width 0.15))
    (fp_line (start 0.973 0.748) (end 0.623 0.748) (layer "F.SilkS") (width 0.15))
    (fp_line (start -0.625 0.748) (end -0.975 0.748) (layer "F.SilkS") (width 0.15))
    (fp_line (start -0.5 -0.426) (end -0.5 0.424) (layer "F.SilkS") (width 0.15))
    (fp_line (start -0.975 -0.75) (end -0.975 -0.45) (layer "F.SilkS") (width 0.15))
    (fp_line (start -0.975 0.748) (end -0.975 0.45) (layer "F.SilkS") (width 0.15))
    (fp_line (start 0.973 -0.75) (end 0.973 -0.45) (layer "F.SilkS") (width 0.15))
    (fp_rect (start -1.6 -0.827) (end 1.599 0.825) (layer "F.CrtYd") (width 0.05) (fill none))
    (fp_line (start -0.85 0.623) (end -0.85 -0.625) (layer "F.Fab") (width 0.15))
    (fp_line (start -0.85 0.623) (end 0.848 0.623) (layer "F.Fab") (width 0.15))
    (fp_line (start 0.848 -0.625) (end 0.848 0.623) (layer "F.Fab") (width 0.15))
    (fp_line (start -0.85 -0.625) (end 0.848 -0.625) (layer "F.Fab") (width 0.15))
    (pad "A" smd roundrect (at 1.05 0 270) (size 0.8 0.6) (layers "F.Cu" "F.Paste" "F.Mask") (roundrect_rratio 0.15)
      (net 107 "/USB-PD/PD_VBUS") (pinfunction "A") (pintype "passive"))
    (pad "K" smd roundrect (at -1.051 0 270) (size 0.8 0.6) (layers "F.Cu" "F.Paste" "F.Mask") (roundrect_rratio 0.15)
      (net 364 "Net-(C153-Pad1)") (pinfunction "K") (pintype "passive"))
  )
	(footprint "sa800u-baseboard-hw-footprints:C_0603_1608Metric" (layer "F.Cu")
    (tedit 5D5E94D2)
    (at 81.97 120.05 -90)
    (descr "Capacitor SMD 0603")
    (tags "capacitor 0603")
    (property "Author" "Antmicro")
    (property "Dielectric" "")
    (property "License" "Apache-2.0")
    (property "MPN" "GRM188R60J226MEA0D")
    (property "Manufacturer" "Murata")
    (property "Sheetfile" "psu.kicad_sch")
    (property "Sheetname" "PSU")
    (property "Val" "22u")
    (property "Voltage" "")
    (attr smd)
    (fp_text reference "C143" (at 1.32 -2.96 -90) (layer "F.SilkS")
      (effects (font (size 0.7 0.7) (thickness 0.15)) (justify left bottom))
    )
    (fp_text value "C_22u_0603" (at 0 1.6 -90) (layer "F.Fab")
      (effects (font (size 0.7 0.7) (thickness 0.15)) (justify left bottom))
    )
    (fp_text user "Author: Antmicro" (at -1.682 4.894 -90) (layer "F.Fab") hide
      (effects (font (size 0.7 0.7) (thickness 0.15)) (justify left bottom))
    )
    (fp_text user "${REFERENCE}" (at -1.682 3.895 -90) (layer "F.Fab") hide
      (effects (font (size 0.7 0.7) (thickness 0.15)) (justify left bottom))
    )
    (fp_text user "License: Apache-2.0" (at -1.682 5.895 -90) (layer "F.Fab") hide
      (effects (font (size 0.7 0.7) (thickness 0.15)) (justify left bottom))
    )
    (fp_line (start -0.3 -0.3) (end 0.3 -0.3) (layer "F.SilkS") (width 0.15))
    (fp_line (start -0.3 0.3) (end 0.3 0.3) (layer "F.SilkS") (width 0.15))
    (fp_rect (start -1.24 -0.7) (end 1.24 0.7) (layer "F.CrtYd") (width 0.05) (fill none))
    (fp_rect (start -0.8 -0.4) (end 0.8 0.4) (layer "F.Fab") (width 0.15) (fill none))
    (pad "1" smd roundrect (at -0.7 0 270) (size 0.6 0.8) (layers "F.Cu" "F.Paste" "F.Mask") (roundrect_rratio 0.2)
      (net 133 "5V_SYS") (pintype "passive"))
    (pad "2" smd roundrect (at 0.7 0 270) (size 0.6 0.8) (layers "F.Cu" "F.Paste" "F.Mask") (roundrect_rratio 0.2)
      (net 1 "GND") (pintype "passive"))
  )
	(footprint "sa800u-baseboard-hw-footprints:R_0402_1005Metric" (layer "F.Cu")
    (tedit 5FD9C158)
    (at 71.6 117.3)
    (descr "Resistor SMD 0402")
    (tags "resistor SMD 0402")
    (property "Author" "Antmicro")
    (property "License" "Apache-2.0")
    (property "MPN" "CR0402-FX-5232GLF")
    (property "Manufacturer" "Bourns")
    (property "Sheetfile" "psu.kicad_sch")
    (property "Sheetname" "PSU")
    (property "Tolerance" "1%")
    (property "Val" "52k3")
    (attr smd)
    (fp_text reference "R141" (at 0.95 4.53) (layer "F.SilkS")
      (effects (font (size 0.7 0.7) (thickness 0.15)) (justify left bottom))
    )
    (fp_text value "R_52k3_0402" (at 0 1.4) (layer "F.Fab")
      (effects (font (size 0.7 0.7) (thickness 0.15)) (justify left bottom))
    )
    (fp_text user "License: Apache-2.0" (at -0.95 5.169) (layer "F.Fab") hide
      (effects (font (size 0.7 0.7) (thickness 0.15)) (justify left bottom))
    )
    (fp_text user "${REFERENCE}" (at -0.95 3.168) (layer "F.Fab") hide
      (effects (font (size 0.7 0.7) (thickness 0.15)) (justify left bottom))
    )
    (fp_text user "Author: Antmicro" (at -0.95 4.169) (layer "F.Fab") hide
      (effects (font (size 0.7 0.7) (thickness 0.15)) (justify left bottom))
    )
    (fp_rect (start -0.93 -0.47) (end 0.93 0.47) (layer "F.CrtYd") (width 0.05) (fill none))
    (fp_rect (start -0.5 -0.25) (end 0.5 0.25) (layer "F.Fab") (width 0.15) (fill none))
    (pad "1" smd roundrect (at -0.485 0) (size 0.59 0.64) (layers "F.Cu" "F.Paste" "F.Mask") (roundrect_rratio 0.25)
      (net 133 "5V_SYS") (pintype "passive"))
    (pad "2" smd roundrect (at 0.485 0) (size 0.59 0.64) (layers "F.Cu" "F.Paste" "F.Mask") (roundrect_rratio 0.25)
      (net 173 "Net-(R141-Pad2)") (pintype "passive"))
  )
	(footprint "sa800u-baseboard-hw-footprints:C_0402_1005Metric" (layer "F.Cu")
    (tedit 616D63CF)
    (at 73.55 114.2)
    (descr "Capacitor SMD 0402")
    (tags "capacitor SMD 0402")
    (property "Author" "Antmicro")
    (property "Dielectric" "X5R")
    (property "License" "Apache-2.0")
    (property "MPN" "GRM155R61H104KE14D")
    (property "Manufacturer" "Murata")
    (property "Sheetfile" "psu.kicad_sch")
    (property "Sheetname" "PSU")
    (property "Val" "100n")
    (property "Voltage" "50V")
    (attr smd)
    (fp_text reference "C133" (at -3.75 0.29) (layer "F.SilkS")
      (effects (font (size 0.7 0.7) (thickness 0.15)) (justify left bottom))
    )
    (fp_text value "C_100n_0402" (at 0 1.4) (layer "F.Fab")
      (effects (font (size 0.7 0.7) (thickness 0.15)) (justify left bottom))
    )
    (fp_text user "${REFERENCE}" (at -0.932 3.168) (layer "F.Fab") hide
      (effects (font (size 0.7 0.7) (thickness 0.15)) (justify left bottom))
    )
    (fp_text user "Author: Antmicro" (at -0.932 4.17) (layer "F.Fab") hide
      (effects (font (size 0.7 0.7) (thickness 0.15)) (justify left bottom))
    )
    (fp_text user "License: Apache-2.0" (at -0.932 5.17) (layer "F.Fab") hide
      (effects (font (size 0.7 0.7) (thickness 0.15)) (justify left bottom))
    )
    (fp_rect (start -0.94 -0.47) (end 0.94 0.47) (layer "F.CrtYd") (width 0.05) (fill none))
    (fp_rect (start -0.499 -0.249) (end 0.499 0.249) (layer "F.Fab") (width 0.15) (fill none))
    (pad "1" smd roundrect (at -0.484 0) (size 0.59 0.64) (layers "F.Cu" "F.Paste" "F.Mask") (roundrect_rratio 0.25)
      (net 358 "Net-(C133-Pad1)") (pintype "passive"))
    (pad "2" smd roundrect (at 0.484 0) (size 0.59 0.64) (layers "F.Cu" "F.Paste" "F.Mask") (roundrect_rratio 0.25)
      (net 359 "Net-(C133-Pad2)") (pintype "passive"))
  )
	(footprint "sa800u-baseboard-hw-footprints:C_0402_1005Metric" (layer "F.Cu")
    (tedit 616D63CF)
    (at 101.549174 104.257734)
    (descr "Capacitor SMD 0402")
    (tags "capacitor SMD 0402")
    (property "Author" "Antmicro")
    (property "DNP" "DNP")
    (property "Dielectric" "")
    (property "License" "Apache-2.0")
    (property "MPN" "GRM155R61A475MEAAD")
    (property "Manufacturer" "Murata")
    (property "Sheetfile" "ethernet-controller.kicad_sch")
    (property "Sheetname" "Ethernet Controller")
    (property "Val" "4u7")
    (property "Voltage" "")
    (attr exclude_from_pos_files)
    (fp_text reference "C9" (at 0.910826 0.362266) (layer "F.SilkS")
      (effects (font (size 0.7 0.7) (thickness 0.15)) (justify left bottom))
    )
    (fp_text value "C_4u7_0402" (at 0 1.4) (layer "F.Fab")
      (effects (font (size 0.7 0.7) (thickness 0.15)) (justify left bottom))
    )
    (fp_text user "${REFERENCE}" (at -0.932 3.168) (layer "F.Fab") hide
      (effects (font (size 0.7 0.7) (thickness 0.15)) (justify left bottom))
    )
    (fp_text user "License: Apache-2.0" (at -0.932 5.17) (layer "F.Fab") hide
      (effects (font (size 0.7 0.7) (thickness 0.15)) (justify left bottom))
    )
    (fp_text user "Author: Antmicro" (at -0.932 4.17) (layer "F.Fab") hide
      (effects (font (size 0.7 0.7) (thickness 0.15)) (justify left bottom))
    )
    (fp_rect (start -0.94 -0.47) (end 0.94 0.47) (layer "F.CrtYd") (width 0.05) (fill none))
    (fp_rect (start -0.499 -0.249) (end 0.499 0.249) (layer "F.Fab") (width 0.15) (fill none))
    (pad "1" smd roundrect (at -0.484 0) (size 0.59 0.64) (layers "F.Cu" "F.Paste" "F.Mask") (roundrect_rratio 0.25)
      (net 177 "/Ethernet Controller/ETH_3V3") (pintype "passive"))
    (pad "2" smd roundrect (at 0.484 0) (size 0.59 0.64) (layers "F.Cu" "F.Paste" "F.Mask") (roundrect_rratio 0.25)
      (net 1 "GND") (pintype "passive"))
  )
	(footprint "sa800u-baseboard-hw-footprints:R_0603_1608Metric" (layer "F.Cu")
    (tedit 5D5D3E92)
    (at 98.73 102.55 180)
    (descr "Resistor SMD 0603")
    (tags "resistor SMD 0603")
    (property "Author" "Antmicro")
    (property "License" "Apache-2.0")
    (property "MPN" "CR0603-FX-1502ELF")
    (property "Manufacturer" "Bourns")
    (property "Sheetfile" "ethernet-controller.kicad_sch")
    (property "Sheetname" "Ethernet Controller")
    (property "Tolerance" "1%")
    (property "Val" "15k")
    (attr smd)
    (fp_text reference "R10" (at 1.07 0.62 180) (layer "F.SilkS")
      (effects (font (size 0.7 0.7) (thickness 0.15)) (justify left bottom))
    )
    (fp_text value "R_15k_0603" (at 0 1.6 180) (layer "F.Fab")
      (effects (font (size 0.7 0.7) (thickness 0.15)) (justify left bottom))
    )
    (fp_text user "${REFERENCE}" (at -1.25 3.898 180) (layer "F.Fab") hide
      (effects (font (size 0.7 0.7) (thickness 0.15)) (justify left bottom))
    )
    (fp_text user "Author: Antmicro" (at -1.25 4.9 180) (layer "F.Fab") hide
      (effects (font (size 0.7 0.7) (thickness 0.15)) (justify left bottom))
    )
    (fp_text user "License: Apache-2.0" (at -1.25 5.9 180) (layer "F.Fab") hide
      (effects (font (size 0.7 0.7) (thickness 0.15)) (justify left bottom))
    )
    (fp_line (start -0.3 -0.3) (end 0.3 -0.3) (layer "F.SilkS") (width 0.15))
    (fp_line (start -0.3 0.3) (end 0.3 0.3) (layer "F.SilkS") (width 0.15))
    (fp_rect (start -1.25 -0.7) (end 1.25 0.7) (layer "F.CrtYd") (width 0.05) (fill none))
    (fp_rect (start -0.8 -0.4) (end 0.8 0.4) (layer "F.Fab") (width 0.15) (fill none))
    (pad "1" smd roundrect (at -0.7 0 180) (size 0.6 0.8) (layers "F.Cu" "F.Paste" "F.Mask") (roundrect_rratio 0.2)
      (net 286 "/Ethernet Controller/ETH_ISOLATEB") (pintype "passive"))
    (pad "2" smd roundrect (at 0.7 0 180) (size 0.6 0.8) (layers "F.Cu" "F.Paste" "F.Mask") (roundrect_rratio 0.2)
      (net 1 "GND") (pintype "passive"))
  )
)
